#ISCELL
  mstr_misc dns *
  *
#ISCELL
  mstr_misc prelim *
  *
#ISCELL
  mstr_symbols cad_note *
  *
#ISCELL
  mstr_symbols intel_corp_bpage *
  *
#ISCELL
  mstr_symbols gnd *
  page229_i1
#ISCELL
  mstr_symbols gnd *
  page229_i10
#CELL
  mstr_discrete cap *
  page229_i11
#CELL
  mstr_misc shunt *
  page229_i12
#ISCELL
  mstr_symbols gnd *
  page229_i13
#CELL
  mstr_discrete cap *
  page229_i14
#ISCELL
  mstr_symbols gnd *
  page229_i15
#CELL
  mstr_discrete cap *
  page229_i16
#ISCELL
  mstr_symbols gnd *
  page229_i17
#CELL
  mstr_discrete cap *
  page229_i18
#ISCELL
  mstr_symbols gnd *
  page229_i19
#CELL
  mstr_discrete cap *
  page229_i2
#ISCELL
  mstr_symbols gnd *
  page229_i20
#CELL
  mstr_discrete cap *
  page229_i21
#ISCELL
  mstr_symbols gnd *
  page229_i22
#CELL
  mstr_discrete cap *
  page229_i23
#CELL
  mstr_discrete res *
  page229_i24
#ISCELL
  mstr_symbols gnd *
  page229_i25
#CELL
  mstr_discrete cap *
  page229_i26
#ISCELL
  mstr_symbols p3v3 *
  page229_i27
#CELL
  dev_discrete cap_a *
  page229_i28
#ISCELL
  mstr_symbols pvtt_ghj *
  page229_i29
#ISCELL
  mstr_standard offpage *
  page229_i3
#CELL
  mstr_discrete res *
  page229_i32
#ISCELL
  mstr_standard offpage *
  page229_i33
#ISCELL
  mstr_symbols pvtt_ghj *
  page229_i34
#ISCELL
  mstr_symbols gnd *
  page229_i35
#CELL
  mstr_vreg mic5166 *
  page229_i37
#CELL
  mstr_discrete res *
  page229_i4
#CELL
  mstr_discrete cap *
  page229_i41
#CELL
  mstr_discrete cap *
  page229_i42
#CELL
  mstr_discrete cap *
  page229_i43
#CELL
  mstr_discrete res *
  page229_i5
#CELL
  mstr_discrete res *
  page229_i6
#ISCELL
  mstr_symbols p3v3 *
  page229_i7
#ISCELL
  mstr_symbols pvddq_ghj *
  page229_i8
#CELL
  mstr_discrete res *
  page229_i9
